(kicad_pcb
	(version 20260206)
	(generator "pcbnew")
	(generator_version "10.0")
	(general
		(thickness 1.6)
		(legacy_teardrops no)
	)
	(paper "A4")
	(title_block
		(title "panther-plus-userver — 13130-1b_20150205.brd")
		(comment 1 "Honey Badger (Wiwynn) / footprints 999-1005 of 1509")
	)
	(layers
		(0 "F.Cu" signal "TOP")
		(4 "In1.Cu" signal "L2")
		(6 "In2.Cu" signal "L3")
		(8 "In3.Cu" signal "L4")
		(10 "In4.Cu" signal "L5")
		(12 "In5.Cu" signal "L6")
		(14 "In6.Cu" signal "L7")
		(16 "In7.Cu" signal "L8")
		(18 "In8.Cu" signal "L9")
		(20 "In9.Cu" signal "L10")
		(22 "In10.Cu" signal "L11")
		(2 "B.Cu" signal "BOTTOM")
		(9 "F.Adhes" user "F.Adhesive")
		(11 "B.Adhes" user "B.Adhesive")
		(13 "F.Paste" user "Package Geometry/Pastemask Top")
		(15 "B.Paste" user "Package Geometry/Pastemask Bottom")
		(5 "F.SilkS" user "Ref Des/Silkscreen Top")
		(7 "B.SilkS" user "Ref Des/Silkscreen Bottom")
		(1 "F.Mask" user "Board Geometry/Soldermask Top")
		(3 "B.Mask" user "Board Geometry/Soldermask Bottom")
		(17 "Dwgs.User" user "User.Drawings")
		(19 "Cmts.User" user "User.Comments")
		(21 "Eco1.User" user "User.Eco1")
		(23 "Eco2.User" user "User.Eco2")
		(25 "Edge.Cuts" user "Board Geometry/Outline")
		(27 "Margin" user)
		(31 "F.CrtYd" user "Package Geometry/Place Bound Top")
		(29 "B.CrtYd" user "Package Geometry/Place Bound Bottom")
		(35 "F.Fab" user "Ref Des/Assembly Top")
		(33 "B.Fab" user "Ref Des/Assembly Bottom")
	)
	(footprint ""
		(layer "B.Cu")
		(at 65.786 -13.589 180)
		(property "Reference" "C306"
			(at 0 0 0)
			(layer "B.SilkS")
			(hide yes)
			(effects
				(font
					(size 1.27 1.27)
				)
				(justify mirror)
			)
		)
		(property "Value" "SCD01U16V2KX-3GP"
			(at -1.8923 -1.2065 180)
			(unlocked yes)
			(layer "B.Fab")
			(hide yes)
			(effects
				(font
					(size 1.016 1.016)
					(thickness 0.1524)
				)
				(justify mirror)
			)
		)
		(property "Device Type" "C402H22"
			(at -1.8923 -2.7305 180)
			(unlocked yes)
			(layer "B.Fab")
			(hide yes)
			(effects
				(font
					(size 1.016 1.016)
					(thickness 0.1524)
				)
				(justify mirror)
			)
		)
		(duplicate_pad_numbers_are_jumpers no)
		(fp_rect
			(start 0.381 0.7366)
			(end -0.381 -0.7366)
			(stroke
				(width 0)
				(type default)
			)
			(fill no)
			(layer "B.CrtYd")
		)
		(fp_rect
			(start 0.381 0.7366)
			(end -0.381 -0.7366)
			(stroke
				(width 0)
				(type default)
			)
			(fill no)
			(layer "B.Fab")
		)
		(pad "1" smd custom
			(at 0 -0.4572)
			(size 0.1143 0.1143)
			(layers "B.Cu" "B.Mask" "B.Paste")
			(net "SATA2_TX_C_DN0")
			(options
				(clearance outline)
				(anchor circle)
			)
			(primitives
				(gr_poly
					(pts
						(arc
							(start -0.254 0.1778)
							(mid -0.239121 0.213721)
							(end -0.2032 0.2286)
						)
						(arc
							(start 0.2032 0.2286)
							(mid 0.239121 0.213721)
							(end 0.254 0.1778)
						)
						(arc
							(start 0.254 -0.1778)
							(mid 0.239121 -0.213721)
							(end 0.2032 -0.2286)
						)
						(arc
							(start -0.2032 -0.2286)
							(mid -0.239121 -0.213721)
							(end -0.254 -0.1778)
						)
					)
					(width 0)
					(fill yes)
				)
			)
		)
		(pad "2" smd custom
			(at 0 0.4572)
			(size 0.1143 0.1143)
			(layers "B.Cu" "B.Mask" "B.Paste")
			(net "SATA2_TX_DN0")
			(options
				(clearance outline)
				(anchor circle)
			)
			(primitives
				(gr_poly
					(pts
						(arc
							(start -0.254 0.1778)
							(mid -0.239121 0.213721)
							(end -0.2032 0.2286)
						)
						(arc
							(start 0.2032 0.2286)
							(mid 0.239121 0.213721)
							(end 0.254 0.1778)
						)
						(arc
							(start 0.254 -0.1778)
							(mid 0.239121 -0.213721)
							(end 0.2032 -0.2286)
						)
						(arc
							(start -0.2032 -0.2286)
							(mid -0.239121 -0.213721)
							(end -0.254 -0.1778)
						)
					)
					(width 0)
					(fill yes)
				)
			)
		)
	)
	(footprint ""
		(layer "B.Cu")
		(at 104.648 -42.7228 -90)
		(property "Reference" "TP24"
			(at 0 0 90)
			(layer "B.SilkS")
			(hide yes)
			(effects
				(font
					(size 1.27 1.27)
				)
				(justify mirror)
			)
		)
		(property "Value" "TPAD24"
			(at 0 -2.9972 270)
			(unlocked yes)
			(layer "B.Fab")
			(hide yes)
			(effects
				(font
					(size 1.016 1.016)
					(thickness 0.1524)
				)
				(justify mirror)
			)
		)
		(property "Device Type" "TPAD24"
			(at 0 -4.5212 270)
			(unlocked yes)
			(layer "B.Fab")
			(hide yes)
			(effects
				(font
					(size 1.016 1.016)
					(thickness 0.1524)
				)
				(justify mirror)
			)
		)
		(duplicate_pad_numbers_are_jumpers no)
		(fp_poly
			(pts
				(arc
					(start 0 -0.3048)
					(mid 0 0.3048)
					(end 0 -0.3048)
				)
			)
			(stroke
				(width 0)
				(type default)
			)
			(fill no)
			(layer "B.CrtYd")
		)
		(fp_poly
			(pts
				(arc
					(start 0 -0.6096)
					(mid 0 0.6096)
					(end 0 -0.6096)
				)
			)
			(stroke
				(width 0)
				(type default)
			)
			(fill no)
			(layer "B.Fab")
		)
		(pad "1" smd circle
			(at 0 0 90)
			(size 0.6096 0.6096)
			(layers "B.Cu" "B.Mask" "B.Paste")
			(net "TP_CPU_RSVD7")
		)
	)
	(footprint ""
		(layer "B.Cu")
		(at 52.6796 -21.8948)
		(property "Reference" "R439"
			(at 0 0 0)
			(layer "B.SilkS")
			(hide yes)
			(effects
				(font
					(size 1.27 1.27)
				)
				(justify mirror)
			)
		)
		(property "Value" "10KR2F-2-GP"
			(at -1.7907 -1.1176 0)
			(unlocked yes)
			(layer "B.Fab")
			(hide yes)
			(effects
				(font
					(size 1.016 1.016)
					(thickness 0.1524)
				)
				(justify mirror)
			)
		)
		(property "Device Type" "R402H16"
			(at -1.7907 -2.6416 0)
			(unlocked yes)
			(layer "B.Fab")
			(hide yes)
			(effects
				(font
					(size 1.016 1.016)
					(thickness 0.1524)
				)
				(justify mirror)
			)
		)
		(duplicate_pad_numbers_are_jumpers no)
		(fp_rect
			(start 0.381 0.8382)
			(end -0.381 -0.8382)
			(stroke
				(width 0)
				(type default)
			)
			(fill no)
			(layer "B.CrtYd")
		)
		(fp_rect
			(start 0.381 0.8382)
			(end -0.381 -0.8382)
			(stroke
				(width 0)
				(type default)
			)
			(fill no)
			(layer "B.Fab")
		)
		(pad "1" smd custom
			(at 0 -0.4318 180)
			(size 0.127 0.127)
			(layers "B.Cu" "B.Mask" "B.Paste")
			(net "P3V3")
			(options
				(clearance outline)
				(anchor circle)
			)
			(primitives
				(gr_poly
					(pts
						(arc
							(start -0.2032 0.2794)
							(mid -0.239121 0.264521)
							(end -0.254 0.2286)
						)
						(arc
							(start -0.254 -0.2286)
							(mid -0.239121 -0.264521)
							(end -0.2032 -0.2794)
						)
						(arc
							(start 0.2032 -0.2794)
							(mid 0.239121 -0.264521)
							(end 0.254 -0.2286)
						)
						(arc
							(start 0.254 0.2286)
							(mid 0.239121 0.264521)
							(end 0.2032 0.2794)
						)
					)
					(width 0)
					(fill yes)
				)
			)
		)
		(pad "2" smd custom
			(at 0 0.4318 180)
			(size 0.127 0.127)
			(layers "B.Cu" "B.Mask" "B.Paste")
			(net "CLKBUFF_SRC_DIV#")
			(options
				(clearance outline)
				(anchor circle)
			)
			(primitives
				(gr_poly
					(pts
						(arc
							(start -0.2032 0.2794)
							(mid -0.239121 0.264521)
							(end -0.254 0.2286)
						)
						(arc
							(start -0.254 -0.2286)
							(mid -0.239121 -0.264521)
							(end -0.2032 -0.2794)
						)
						(arc
							(start 0.2032 -0.2794)
							(mid 0.239121 -0.264521)
							(end 0.254 -0.2286)
						)
						(arc
							(start 0.254 0.2286)
							(mid 0.239121 0.264521)
							(end 0.2032 0.2794)
						)
					)
					(width 0)
					(fill yes)
				)
			)
		)
	)
	(footprint ""
		(layer "B.Cu")
		(at 87.503 -68.453 -90)
		(property "Reference" "PR31"
			(at 0 0 90)
			(layer "B.SilkS")
			(hide yes)
			(effects
				(font
					(size 1.27 1.27)
				)
				(justify mirror)
			)
		)
		(property "Value" "0R6J-3-GP"
			(at 0.0508 -4.8514 270)
			(unlocked yes)
			(layer "B.Fab")
			(hide yes)
			(effects
				(font
					(size 1.016 1.016)
					(thickness 0.1524)
				)
				(justify mirror)
			)
		)
		(property "Device Type" "R1206H28"
			(at 0 -6.3754 270)
			(unlocked yes)
			(layer "B.Fab")
			(hide yes)
			(effects
				(font
					(size 1.016 1.016)
					(thickness 0.1524)
				)
				(justify mirror)
			)
		)
		(duplicate_pad_numbers_are_jumpers no)
		(fp_line
			(start -0.7239 0.381)
			(end -0.7239 -0.381)
			(stroke
				(width 0.1524)
				(type default)
			)
			(layer "B.SilkS")
		)
		(fp_line
			(start 0.7239 0.381)
			(end -0.7239 0.381)
			(stroke
				(width 0.1524)
				(type default)
			)
			(layer "B.SilkS")
		)
		(fp_line
			(start -0.7239 -0.381)
			(end 0.7239 -0.381)
			(stroke
				(width 0.1524)
				(type default)
			)
			(layer "B.SilkS")
		)
		(fp_line
			(start 0.7239 -0.381)
			(end 0.7239 0.381)
			(stroke
				(width 0.1524)
				(type default)
			)
			(layer "B.SilkS")
		)
		(fp_poly
			(pts
				(xy 0.7239 0.381) (xy -0.7239 0.381) (xy -0.7239 -0.381) (xy 0.7239 -0.381)
			)
			(stroke
				(width 0)
				(type default)
			)
			(fill yes)
			(layer "B.SilkS")
		)
		(fp_rect
			(start 1.0541 1.9812)
			(end -1.0541 -1.9812)
			(stroke
				(width 0)
				(type default)
			)
			(fill no)
			(layer "B.CrtYd")
		)
		(fp_rect
			(start 1.0541 1.9812)
			(end -1.0541 -1.9812)
			(stroke
				(width 0)
				(type default)
			)
			(fill no)
			(layer "B.Fab")
		)
		(pad "1" smd rect
			(at 0 -1.3462 90)
			(size 1.8542 1.016)
			(layers "B.Cu" "B.Mask" "B.Paste")
			(net "VR_P1V1_PVIN")
		)
		(pad "2" smd rect
			(at 0 1.3462 90)
			(size 1.8542 1.016)
			(layers "B.Cu" "B.Mask" "B.Paste")
			(net "P3V3_STBY")
		)
	)
	(footprint ""
		(layer "B.Cu")
		(at 18.923 -45.466)
		(property "Reference" "Q17"
			(at 0 0 0)
			(layer "B.SilkS")
			(hide yes)
			(effects
				(font
					(size 1.27 1.27)
				)
				(justify mirror)
			)
		)
		(property "Value" "2N7002A-7-GP"
			(at 4.3561 -5.7912 0)
			(unlocked yes)
			(layer "B.Fab")
			(hide yes)
			(effects
				(font
					(size 1.016 1.016)
					(thickness 0.1524)
				)
				(justify mirror)
			)
		)
		(property "Device Type" "SOT23DGS2D4H48"
			(at 4.3561 -7.3152 0)
			(unlocked yes)
			(layer "B.Fab")
			(hide yes)
			(effects
				(font
					(size 1.016 1.016)
					(thickness 0.1524)
				)
				(justify mirror)
			)
		)
		(duplicate_pad_numbers_are_jumpers no)
		(fp_line
			(start -1.7145 -0.4445)
			(end 1.7145 -0.4445)
			(stroke
				(width 0.1524)
				(type default)
			)
			(layer "B.SilkS")
		)
		(fp_line
			(start -1.7145 0.4445)
			(end -1.7145 -0.4445)
			(stroke
				(width 0.1524)
				(type default)
			)
			(layer "B.SilkS")
		)
		(fp_line
			(start 1.7145 -0.4445)
			(end 1.7145 0.4445)
			(stroke
				(width 0.1524)
				(type default)
			)
			(layer "B.SilkS")
		)
		(fp_line
			(start 1.7145 0.4445)
			(end -1.7145 0.4445)
			(stroke
				(width 0.1524)
				(type default)
			)
			(layer "B.SilkS")
		)
		(fp_poly
			(pts
				(xy 1.4224 1.5621) (xy 1.4224 0.9017) (xy 1.7145 0.9017) (xy 1.7145 -0.9017) (xy 0.4699 -0.9017)
				(xy 0.4699 -1.5621) (xy -0.4699 -1.5621) (xy -0.4699 -0.9017) (xy -1.7145 -0.9017) (xy -1.7145 0.9017)
				(xy -1.4224 0.9017) (xy -1.4224 1.5621) (xy -0.4826 1.5621) (xy -0.4826 0.9017) (xy 0.4826 0.9017)
				(xy 0.4826 1.5621)
			)
			(stroke
				(width 0)
				(type default)
			)
			(fill no)
			(layer "B.CrtYd")
		)
		(fp_poly
			(pts
				(xy 1.4224 1.5621) (xy 1.4224 0.9017) (xy 1.7145 0.9017) (xy 1.7145 -0.9017) (xy 0.4699 -0.9017)
				(xy 0.4699 -1.5621) (xy -0.4699 -1.5621) (xy -0.4699 -0.9017) (xy -1.7145 -0.9017) (xy -1.7145 0.9017)
				(xy -1.4224 0.9017) (xy -1.4224 1.5621) (xy -0.4826 1.5621) (xy -0.4826 0.9017) (xy 0.4826 0.9017)
				(xy 0.4826 1.5621)
			)
			(stroke
				(width 0)
				(type default)
			)
			(fill no)
			(layer "B.Fab")
		)
		(pad "D" smd custom
			(at 0 -1.069086 180)
			(size 0.17145 0.17145)
			(layers "B.Cu" "B.Mask" "B.Paste")
			(net "P3V3_DISCHARGE_D")
			(options
				(clearance outline)
				(anchor circle)
			)
			(primitives
				(gr_poly
					(pts
						(arc
							(start -0.1397 -0.3683)
							(mid -0.283384 -0.308784)
							(end -0.3429 -0.1651)
						)
						(arc
							(start -0.3429 0.1651)
							(mid -0.283384 0.308784)
							(end -0.1397 0.3683)
						)
						(arc
							(start 0.1397 0.3683)
							(mid 0.283384 0.308784)
							(end 0.3429 0.1651)
						)
						(arc
							(start 0.3429 -0.1651)
							(mid 0.283384 -0.308784)
							(end 0.1397 -0.3683)
						)
					)
					(width 0)
					(fill yes)
				)
			)
		)
		(pad "G" smd custom
			(at 0.94996 1.069086 180)
			(size 0.17145 0.17145)
			(layers "B.Cu" "B.Mask" "B.Paste")
			(net "SW_P3V3_LV_G5")
			(options
				(clearance outline)
				(anchor circle)
			)
			(primitives
				(gr_poly
					(pts
						(arc
							(start -0.1397 -0.3683)
							(mid -0.283384 -0.308784)
							(end -0.3429 -0.1651)
						)
						(arc
							(start -0.3429 0.1651)
							(mid -0.283384 0.308784)
							(end -0.1397 0.3683)
						)
						(arc
							(start 0.1397 0.3683)
							(mid 0.283384 0.308784)
							(end 0.3429 0.1651)
						)
						(arc
							(start 0.3429 -0.1651)
							(mid 0.283384 -0.308784)
							(end 0.1397 -0.3683)
						)
					)
					(width 0)
					(fill yes)
				)
			)
		)
		(pad "S" smd custom
			(at -0.94996 1.069086 180)
			(size 0.17145 0.17145)
			(layers "B.Cu" "B.Mask" "B.Paste")
			(net "GND")
			(options
				(clearance outline)
				(anchor circle)
			)
			(primitives
				(gr_poly
					(pts
						(arc
							(start -0.1397 -0.3683)
							(mid -0.283384 -0.308784)
							(end -0.3429 -0.1651)
						)
						(arc
							(start -0.3429 0.1651)
							(mid -0.283384 0.308784)
							(end -0.1397 0.3683)
						)
						(arc
							(start 0.1397 0.3683)
							(mid 0.283384 0.308784)
							(end 0.3429 0.1651)
						)
						(arc
							(start 0.3429 -0.1651)
							(mid 0.283384 -0.308784)
							(end 0.1397 -0.3683)
						)
					)
					(width 0)
					(fill yes)
				)
			)
		)
	)
	(footprint ""
		(layer "B.Cu")
		(at 109.093 -66.675 -90)
		(property "Reference" "CN7"
			(at 0 0 90)
			(layer "B.SilkS")
			(hide yes)
			(effects
				(font
					(size 1.27 1.27)
				)
				(justify mirror)
			)
		)
		(property "Value" "HR-CON2-6-GP"
			(at 4.6355 -7.3787 270)
			(unlocked yes)
			(layer "B.Fab")
			(hide yes)
			(effects
				(font
					(size 1.016 1.016)
					(thickness 0.1524)
				)
				(justify mirror)
			)
		)
		(property "Device Type" "A1001WV-S-02PN6BT1TS2L"
			(at 4.6355 -8.9027 270)
			(unlocked yes)
			(layer "B.Fab")
			(hide yes)
			(effects
				(font
					(size 1.016 1.016)
					(thickness 0.1524)
				)
				(justify mirror)
			)
		)
		(duplicate_pad_numbers_are_jumpers no)
		(fp_poly
			(pts
				(xy -0.489458 -3.443986) (xy -1.124458 -4.078986) (xy 0.145542 -4.078986)
			)
			(stroke
				(width 0)
				(type default)
			)
			(fill yes)
			(layer "B.SilkS")
		)
		(fp_poly
			(pts
				(xy 0.999998 -1.547114) (xy 0.999998 1.0287) (xy -0.999998 1.0287) (xy -0.999998 -1.547114)
			)
			(stroke
				(width 0)
				(type default)
			)
			(fill yes)
			(layer "B.SilkS")
		)
		(fp_poly
			(pts
				(xy 2.5273 1.0287) (xy 2.5273 -2.5654) (xy 0.9398 -2.5654) (xy 0.9398 -3.4417) (xy -0.9398 -3.4417)
				(xy -0.9398 -2.5654) (xy -2.5273 -2.5654) (xy -2.5273 1.0287)
			)
			(stroke
				(width 0)
				(type default)
			)
			(fill no)
			(layer "B.CrtYd")
		)
		(fp_poly
			(pts
				(xy 2.5273 1.0287) (xy 2.5273 -2.5654) (xy 0.9398 -2.5654) (xy 0.9398 -3.4417) (xy -0.9398 -3.4417)
				(xy -0.9398 -2.5654) (xy -2.5273 -2.5654) (xy -2.5273 1.0287)
			)
			(stroke
				(width 0)
				(type default)
			)
			(fill no)
			(layer "B.Fab")
		)
		(pad "1" smd rect
			(at -0.500126 -2.525014 90)
			(size 0.6096 1.5494)
			(layers "B.Cu" "B.Mask" "B.Paste")
			(net "GND")
		)
		(pad "2" smd rect
			(at 0.500126 -2.525014 90)
			(size 0.6096 1.5494)
			(layers "B.Cu" "B.Mask" "B.Paste")
			(net "P3V0_BAT")
		)
		(pad "PTH1" smd rect
			(at -1.800098 0 90)
			(size 1.1938 1.8034)
			(layers "B.Cu" "B.Mask" "B.Paste")
			(net "GND")
		)
		(pad "PTH2" smd rect
			(at 1.800098 0 90)
			(size 1.1938 1.8034)
			(layers "B.Cu" "B.Mask" "B.Paste")
			(net "GND")
		)
	)
	(footprint ""
		(layer "B.Cu")
		(at 95.885 -33.782)
		(property "Reference" "C215"
			(at 0 0 0)
			(layer "B.SilkS")
			(hide yes)
			(effects
				(font
					(size 1.27 1.27)
				)
				(justify mirror)
			)
		)
		(property "Value" "SC1U10V2KX-1GP"
			(at -1.1811 -2.7051 0)
			(unlocked yes)
			(layer "B.Fab")
			(hide yes)
			(effects
				(font
					(size 1.016 1.016)
					(thickness 0.1524)
				)
				(justify mirror)
			)
		)
		(property "Device Type" "C402H22"
			(at -1.1811 -4.2291 0)
			(unlocked yes)
			(layer "B.Fab")
			(hide yes)
			(effects
				(font
					(size 1.016 1.016)
					(thickness 0.1524)
				)
				(justify mirror)
			)
		)
		(duplicate_pad_numbers_are_jumpers no)
		(fp_rect
			(start 0.381 0.7366)
			(end -0.381 -0.7366)
			(stroke
				(width 0)
				(type default)
			)
			(fill no)
			(layer "B.CrtYd")
		)
		(fp_rect
			(start 0.381 0.7366)
			(end -0.381 -0.7366)
			(stroke
				(width 0)
				(type default)
			)
			(fill no)
			(layer "B.Fab")
		)
		(pad "1" smd custom
			(at 0 -0.4572 180)
			(size 0.1143 0.1143)
			(layers "B.Cu" "B.Mask" "B.Paste")
			(net "P1V35")
			(options
				(clearance outline)
				(anchor circle)
			)
			(primitives
				(gr_poly
					(pts
						(arc
							(start -0.254 0.1778)
							(mid -0.239121 0.213721)
							(end -0.2032 0.2286)
						)
						(arc
							(start 0.2032 0.2286)
							(mid 0.239121 0.213721)
							(end 0.254 0.1778)
						)
						(arc
							(start 0.254 -0.1778)
							(mid 0.239121 -0.213721)
							(end 0.2032 -0.2286)
						)
						(arc
							(start -0.2032 -0.2286)
							(mid -0.239121 -0.213721)
							(end -0.254 -0.1778)
						)
					)
					(width 0)
					(fill yes)
				)
			)
		)
		(pad "2" smd custom
			(at 0 0.4572 180)
			(size 0.1143 0.1143)
			(layers "B.Cu" "B.Mask" "B.Paste")
			(net "GND")
			(options
				(clearance outline)
				(anchor circle)
			)
			(primitives
				(gr_poly
					(pts
						(arc
							(start -0.254 0.1778)
							(mid -0.239121 0.213721)
							(end -0.2032 0.2286)
						)
						(arc
							(start 0.2032 0.2286)
							(mid 0.239121 0.213721)
							(end 0.254 0.1778)
						)
						(arc
							(start 0.254 -0.1778)
							(mid 0.239121 -0.213721)
							(end 0.2032 -0.2286)
						)
						(arc
							(start -0.2032 -0.2286)
							(mid -0.239121 -0.213721)
							(end -0.254 -0.1778)
						)
					)
					(width 0)
					(fill yes)
				)
			)
		)
	)
)
